# S9S_MB_2U (Grand Teton) — schematic netlist excerpt (pin names and nets, part order shuffled) for the footprints in the layout excerpt that follows; sources: Cadence DE-HDL packaged netlist, KiCad conversion of 03242023_DA0F0TMBIJ0_F0T_Motherboard_J_brd_V01_OCP.brd

C171  Q_CAP  0.047UF 25V 10% X7R  pkg C0402  page 210 : A = P3V3_AUX_CLK_GEN_VDD_CK440 ; B = GND
R2422  Q_RES  33.2 1% CHIP  pkg 0402LF  page 240 : A = SMB_VR_SENSOR_3V3AUX_SDA ; B = SMB_VR_3V3AUX_SDA_R0

(kicad_pcb
	(version 20260206)
	(generator "pcbnew")
	(generator_version "10.0")
	(general
		(thickness 1.6)
		(legacy_teardrops no)
	)
	(paper "A4")
	(title_block
		(title "03242023_DA0F0TMBIJ0_F0T_Motherboard_J_brd_V01_OCP.brd")
		(comment 1 "Grand Teton / footprints 5004-5005 of 6105")
	)
	(layers
		(0 "F.Cu" signal "TOP")
		(4 "In1.Cu" signal "GND")
		(6 "In2.Cu" signal "IN1")
		(8 "In3.Cu" signal "GND1")
		(10 "In4.Cu" signal "IN2")
		(12 "In5.Cu" signal "GND2")
		(14 "In6.Cu" signal "IN3")
		(16 "In7.Cu" signal "GND3")
		(18 "In8.Cu" signal "VCC")
		(20 "In9.Cu" signal "VCC1")
		(22 "In10.Cu" signal "GND4")
		(24 "In11.Cu" signal "IN4")
		(26 "In12.Cu" signal "GND5")
		(28 "In13.Cu" signal "IN5")
		(30 "In14.Cu" signal "GND6")
		(32 "In15.Cu" signal "IN6")
		(34 "In16.Cu" signal "GND7")
		(2 "B.Cu" signal "BOTTOM")
		(9 "F.Adhes" user "F.Adhesive")
		(11 "B.Adhes" user "B.Adhesive")
		(13 "F.Paste" user "Package Geometry/Pastemask Top")
		(15 "B.Paste" user "Package Geometry/Pastemask Bottom")
		(5 "F.SilkS" user "Ref Des/Silkscreen Top")
		(7 "B.SilkS" user "Ref Des/Silkscreen Bottom")
		(1 "F.Mask" user "Board Geometry/Soldermask Top")
		(3 "B.Mask" user "Board Geometry/Soldermask Bottom")
		(17 "Dwgs.User" user "User.Drawings")
		(19 "Cmts.User" user "User.Comments")
		(21 "Eco1.User" user "User.Eco1")
		(23 "Eco2.User" user "User.Eco2")
		(25 "Edge.Cuts" user "Board Geometry/Outline")
		(27 "Margin" user)
		(31 "F.CrtYd" user "Package Geometry/Place Bound Top")
		(29 "B.CrtYd" user "Package Geometry/Place Bound Bottom")
		(35 "F.Fab" user "Ref Des/Assembly Top")
		(33 "B.Fab" user "Ref Des/Assembly Bottom")
	)
	(footprint ""
		(layer "B.Cu")
		(at 179.729638 -13.762228 90)
		(property "Reference" "R2422"
			(at 0 0 90)
			(layer "B.SilkS")
			(hide yes)
			(effects
				(font
					(size 1.27 1.27)
				)
				(justify mirror)
			)
		)
		(property "Value" ""
			(at 0 0 90)
			(layer "B.Fab")
			(effects
				(font
					(size 1.27 1.27)
				)
				(justify mirror)
			)
		)
		(duplicate_pad_numbers_are_jumpers no)
		(fp_line
			(start 0.7874 -0.4064)
			(end -0.7874 -0.4064)
			(stroke
				(width 0.1524)
				(type default)
			)
			(layer "B.SilkS")
		)
		(fp_line
			(start -0.7874 -0.4064)
			(end -0.7874 0.4064)
			(stroke
				(width 0.1524)
				(type default)
			)
			(layer "B.SilkS")
		)
		(fp_line
			(start 0.7874 0.4064)
			(end 0.7874 -0.4064)
			(stroke
				(width 0.1524)
				(type default)
			)
			(layer "B.SilkS")
		)
		(fp_line
			(start -0.7874 0.4064)
			(end 0.7874 0.4064)
			(stroke
				(width 0.1524)
				(type default)
			)
			(layer "B.SilkS")
		)
		(fp_line
			(start 0.67945 -0.305054)
			(end 0.12065 -0.305054)
			(stroke
				(width 0.1)
				(type default)
			)
			(layer "B.Fab")
		)
		(fp_line
			(start 0.12065 -0.305054)
			(end 0.12065 -0.2794)
			(stroke
				(width 0.1)
				(type default)
			)
			(layer "B.Fab")
		)
		(fp_line
			(start -0.12065 -0.3048)
			(end -0.67945 -0.3048)
			(stroke
				(width 0.1)
				(type default)
			)
			(layer "B.Fab")
		)
		(fp_line
			(start -0.67945 -0.3048)
			(end -0.67945 0.3048)
			(stroke
				(width 0.1)
				(type default)
			)
			(layer "B.Fab")
		)
		(fp_line
			(start 0.12065 -0.2794)
			(end -0.12065 -0.2794)
			(stroke
				(width 0.1)
				(type default)
			)
			(layer "B.Fab")
		)
		(fp_line
			(start -0.12065 -0.2794)
			(end -0.12065 -0.3048)
			(stroke
				(width 0.1)
				(type default)
			)
			(layer "B.Fab")
		)
		(fp_line
			(start 0.12065 0.2794)
			(end 0.12065 0.3048)
			(stroke
				(width 0.1)
				(type default)
			)
			(layer "B.Fab")
		)
		(fp_line
			(start -0.120396 0.2794)
			(end 0.12065 0.2794)
			(stroke
				(width 0.1)
				(type default)
			)
			(layer "B.Fab")
		)
		(fp_line
			(start 0.67945 0.3048)
			(end 0.67945 -0.305054)
			(stroke
				(width 0.1)
				(type default)
			)
			(layer "B.Fab")
		)
		(fp_line
			(start 0.12065 0.3048)
			(end 0.67945 0.3048)
			(stroke
				(width 0.1)
				(type default)
			)
			(layer "B.Fab")
		)
		(fp_line
			(start -0.120396 0.3048)
			(end -0.120396 0.2794)
			(stroke
				(width 0.1)
				(type default)
			)
			(layer "B.Fab")
		)
		(fp_line
			(start -0.67945 0.3048)
			(end -0.120396 0.3048)
			(stroke
				(width 0.1)
				(type default)
			)
			(layer "B.Fab")
		)
		(pad "1" smd circle
			(at 0.40005 0 270)
			(size 0 0)
			(layers "B.Cu" "B.Mask" "B.Paste")
			(net "SMB_VR_SENSOR_3V3AUX_SDA")
		)
		(pad "2" smd circle
			(at -0.40005 0 270)
			(size 0 0)
			(layers "B.Cu" "B.Mask" "B.Paste")
			(net "SMB_VR_3V3AUX_SDA_R0")
		)
	)
	(footprint ""
		(layer "B.Cu")
		(at 258.953 -98.008948)
		(property "Reference" "C171"
			(at 0 0 0)
			(layer "B.SilkS")
			(hide yes)
			(effects
				(font
					(size 1.27 1.27)
				)
				(justify mirror)
			)
		)
		(property "Value" ""
			(at 0 0 0)
			(layer "B.Fab")
			(effects
				(font
					(size 1.27 1.27)
				)
				(justify mirror)
			)
		)
		(duplicate_pad_numbers_are_jumpers no)
		(fp_line
			(start -0.7874 -0.4064)
			(end -0.7874 0.4064)
			(stroke
				(width 0.1524)
				(type default)
			)
			(layer "B.SilkS")
		)
		(fp_line
			(start -0.7874 0.4064)
			(end 0.7874 0.4064)
			(stroke
				(width 0.1524)
				(type default)
			)
			(layer "B.SilkS")
		)
		(fp_line
			(start 0.7874 -0.4064)
			(end -0.7874 -0.4064)
			(stroke
				(width 0.1524)
				(type default)
			)
			(layer "B.SilkS")
		)
		(fp_line
			(start 0.7874 0.4064)
			(end 0.7874 -0.4064)
			(stroke
				(width 0.1524)
				(type default)
			)
			(layer "B.SilkS")
		)
		(fp_line
			(start -0.67945 -0.3048)
			(end -0.67945 0.3048)
			(stroke
				(width 0.1)
				(type default)
			)
			(layer "B.Fab")
		)
		(fp_line
			(start -0.67945 0.3048)
			(end -0.120396 0.3048)
			(stroke
				(width 0.1)
				(type default)
			)
			(layer "B.Fab")
		)
		(fp_line
			(start -0.12065 -0.3048)
			(end -0.67945 -0.3048)
			(stroke
				(width 0.1)
				(type default)
			)
			(layer "B.Fab")
		)
		(fp_line
			(start -0.12065 -0.2794)
			(end -0.12065 -0.3048)
			(stroke
				(width 0.1)
				(type default)
			)
			(layer "B.Fab")
		)
		(fp_line
			(start -0.120396 0.2794)
			(end 0.12065 0.2794)
			(stroke
				(width 0.1)
				(type default)
			)
			(layer "B.Fab")
		)
		(fp_line
			(start -0.120396 0.3048)
			(end -0.120396 0.2794)
			(stroke
				(width 0.1)
				(type default)
			)
			(layer "B.Fab")
		)
		(fp_line
			(start 0.12065 -0.305054)
			(end 0.12065 -0.2794)
			(stroke
				(width 0.1)
				(type default)
			)
			(layer "B.Fab")
		)
		(fp_line
			(start 0.12065 -0.2794)
			(end -0.12065 -0.2794)
			(stroke
				(width 0.1)
				(type default)
			)
			(layer "B.Fab")
		)
		(fp_line
			(start 0.12065 0.2794)
			(end 0.12065 0.3048)
			(stroke
				(width 0.1)
				(type default)
			)
			(layer "B.Fab")
		)
		(fp_line
			(start 0.12065 0.3048)
			(end 0.67945 0.3048)
			(stroke
				(width 0.1)
				(type default)
			)
			(layer "B.Fab")
		)
		(fp_line
			(start 0.67945 -0.305054)
			(end 0.12065 -0.305054)
			(stroke
				(width 0.1)
				(type default)
			)
			(layer "B.Fab")
		)
		(fp_line
			(start 0.67945 0.3048)
			(end 0.67945 -0.305054)
			(stroke
				(width 0.1)
				(type default)
			)
			(layer "B.Fab")
		)
		(pad "1" smd circle
			(at 0.40005 0 180)
			(size 0 0)
			(layers "B.Cu" "B.Mask" "B.Paste")
			(net "P3V3_AUX_CLK_GEN_VDD_CK440")
		)
		(pad "2" smd circle
			(at -0.40005 0 180)
			(size 0 0)
			(layers "B.Cu" "B.Mask" "B.Paste")
			(net "GND")
		)
	)
)
